FILE_TYPE = MACRO_DRAWING;
SET COLOR_WIRE YELLOW;
SET COLOR_PROP MONO;
SET COLOR_DOT WHITE;
SET COLOR_ARC YELLOW;
SET COLOR_BODY GREEN;
SET COLOR_NOTE MONO;
SET PROP_DISPLAY VALUE;
SET PAGE_NUMBER P171;
FORCEADD INTEL_CORP_BPAGE..1
(2650 500);
FORCEPROP 1 LAST CUSTOM_TXT_CDS <CURRENT_DESIGN_SHEET> OF <TOTAL_DESIGN_SHEETS>
J 0
(2150 525);
PAINT GREEN (2150 525);
FORCEPROP 1 LAST CUSTOM_TXT_CDS <CON_LAST_MODIFIED>
J 0
(725 850);
PAINT GREEN (725 850);
FORCEPROP 2 LAST CUSTOM_TXT_CDS <XR_PAGE_TITLE>
J 0
(-5240 5750);
DISPLAY 0.638298 (-5240 5750);
PAINT PINK (-5240 5750);
DISPLAY INVISIBLE (-5240 5750);
FORCEPROP 1 LAST SCH_ADDRESS3 Santa Clara, CA 95052-8119
J 0
(-1325 525);
DISPLAY 0.617021 (-1325 525);
PAINT GREEN (-1325 525);
FORCEPROP 1 LAST SCH_ADDRESS2 P.O. BOX 58119
J 0
(-1325 575);
DISPLAY 0.617021 (-1325 575);
PAINT GREEN (-1325 575);
FORCEPROP 1 LAST SCH_ADDRESS1 2200 Mission College Blvd.
J 0
(-1325 625);
DISPLAY 0.617021 (-1325 625);
PAINT GREEN (-1325 625);
FORCEPROP 1 LAST SCH_TITLE SPARE
J 0
(-5300 550);
DISPLAY 1.212766 (-5300 550);
PAINT ORANGE (-5300 550);
FORCEPROP 1 LAST SCH_NUMBER H4694802
J 0
(1350 650);
DISPLAY 1.212766 (1350 650);
PAINT YELLOW (1350 650);
FORCEPROP 1 LAST SCH_DEPT BESD
J 1
(-1800 600);
DISPLAY 1.212766 (-1800 600);
PAINT YELLOW (-1800 600);
FORCEPROP 1 LAST SCH_REV 2.420
J 0
(2400 650);
DISPLAY 0.978723 (2400 650);
PAINT YELLOW (2400 650);
FORCEPROP 2 LAST PAGE_BORDER TRUE
J 0
(-5240 5750);
DISPLAY 0.851064 (-5240 5750);
PAINT PINK (-5240 5750);
DISPLAY INVISIBLE (-5240 5750);
FORCEPROP 2 LAST CDS_LIB mstr_symbols
J 0
(2650 500);
PAINT MONO (2650 500);
DISPLAY INVISIBLE (2650 500);
FORCEPROP 1 LAST COMMENT_BODY TRUE
J 0
(2662 512);
DISPLAY 0.468085 (2662 512);
PAINT GREEN (2662 512);
DISPLAY INVISIBLE (2662 512);
FORCEPROP 1 LAST CDS_CON_LAST_MODIFIED Tue Dec 01 11:48:54 2015
J 0
(1225 825);
PAINT ORANGE (1225 825);
DISPLAY INVISIBLE (1225 825);
FORCEPROP 2 LAST CDS_XR_PAGE_TITLE CR-171 : @BASEBOARD_FAB2_LIB.BASEBOARD_FAB2(SCH_1):PAGE171
J 0
(-5240 5750);
DISPLAY 0.638298 (-5240 5750);
PAINT PINK (-5240 5750);
DISPLAY INVISIBLE (-5240 5750);
QUIT
